FILE_TYPE=LIBRARY_PARTS;
PRIMITIVE 'CAPTIVE_SCREW','CAPTIVE_SCREW_TH';
  PIN
  END_PIN;
  BODY
    CLASS='MECHANICAL';
    PART_NAME='CAPTIVE_SCREW';
    PINCOUNT='0';
    PHYS_DES_PREFIX='RM';    
  END_BODY;
END_PRIMITIVE;
END.
